# T6G (Grand Teton) — schematic netlist excerpt (pin names and nets, part order shuffled) for the footprints in the layout excerpt that follows; sources: Cadence DE-HDL packaged netlist, KiCad conversion of 04192023_DAF0TMB3IC0_F0TG_MB_C_brd_V02_OCP.brd

R1060  Q_RES  1K 1% CHIP  pkg 0201LF  page 298 : A = RT_CPU0_P2_ADDR1 ; B = GND
R3534  Q_RES  33.2 1% CHIP  pkg 0402LF  page 148 : A = SMB_E1S_3V3AUX_ISO_SDA_R ; B = SMB_E1S_3V3AUX_ISO_SDA
PR832  Q_RES  0 5% CHIP  pkg 0402LF  page 190 : A = P3V3_AUX_MODE ; B = GND

(kicad_pcb
	(version 20260206)
	(generator "pcbnew")
	(generator_version "10.0")
	(general
		(thickness 1.6)
		(legacy_teardrops no)
	)
	(paper "A4")
	(title_block
		(title "04192023_DAF0TMB3IC0_F0TG_MB_C_brd_V02_OCP.brd")
		(comment 1 "Grand Teton / footprints 1465-1467 of 8354")
	)
	(layers
		(0 "F.Cu" signal "TOP")
		(4 "In1.Cu" signal "GND")
		(6 "In2.Cu" signal "IN1")
		(8 "In3.Cu" signal "GND1")
		(10 "In4.Cu" signal "IN2")
		(12 "In5.Cu" signal "GND2")
		(14 "In6.Cu" signal "IN3")
		(16 "In7.Cu" signal "GND3")
		(18 "In8.Cu" signal "VCC")
		(20 "In9.Cu" signal "VCC1")
		(22 "In10.Cu" signal "GND4")
		(24 "In11.Cu" signal "IN4")
		(26 "In12.Cu" signal "GND5")
		(28 "In13.Cu" signal "IN5")
		(30 "In14.Cu" signal "GND6")
		(32 "In15.Cu" signal "IN6")
		(34 "In16.Cu" signal "GND7")
		(2 "B.Cu" signal "BOTTOM")
		(9 "F.Adhes" user "F.Adhesive")
		(11 "B.Adhes" user "B.Adhesive")
		(13 "F.Paste" user "Package Geometry/Pastemask Top")
		(15 "B.Paste" user "Package Geometry/Pastemask Bottom")
		(5 "F.SilkS" user "Ref Des/Silkscreen Top")
		(7 "B.SilkS" user "Ref Des/Silkscreen Bottom")
		(1 "F.Mask" user "Board Geometry/Soldermask Top")
		(3 "B.Mask" user "Board Geometry/Soldermask Bottom")
		(17 "Dwgs.User" user "User.Drawings")
		(19 "Cmts.User" user "User.Comments")
		(21 "Eco1.User" user "User.Eco1")
		(23 "Eco2.User" user "User.Eco2")
		(25 "Edge.Cuts" user "Board Geometry/Outline")
		(27 "Margin" user)
		(31 "F.CrtYd" user "Package Geometry/Place Bound Top")
		(29 "B.CrtYd" user "Package Geometry/Place Bound Bottom")
		(35 "F.Fab" user "Ref Des/Assembly Top")
		(33 "B.Fab" user "Ref Des/Assembly Bottom")
	)
	(footprint ""
		(layer "F.Cu")
		(at 426.979588 -390.68629)
		(property "Reference" "R1060"
			(at 0 0 0)
			(layer "F.SilkS")
			(hide yes)
			(effects
				(font
					(size 1.27 1.27)
				)
			)
		)
		(property "Value" ""
			(at 0 0 0)
			(layer "F.Fab")
			(effects
				(font
					(size 1.27 1.27)
				)
			)
		)
		(duplicate_pad_numbers_are_jumpers no)
		(fp_line
			(start -0.32512 -0.175006)
			(end 0.32512 -0.175006)
			(stroke
				(width 0.1)
				(type default)
			)
			(layer "F.Fab")
		)
		(fp_line
			(start -0.32512 0.175006)
			(end -0.32512 -0.175006)
			(stroke
				(width 0.1)
				(type default)
			)
			(layer "F.Fab")
		)
		(fp_line
			(start 0.32512 -0.175006)
			(end 0.32512 0.175006)
			(stroke
				(width 0.1)
				(type default)
			)
			(layer "F.Fab")
		)
		(fp_line
			(start 0.32512 0.175006)
			(end -0.32512 0.175006)
			(stroke
				(width 0.1)
				(type default)
			)
			(layer "F.Fab")
		)
		(pad "1" smd rect
			(at -0.2667 0)
			(size 0.3048 0.381)
			(layers "F.Cu" "F.Mask" "F.Paste")
			(net "RT_CPU0_P2_ADDR1")
		)
		(pad "2" smd rect
			(at 0.2667 0 180)
			(size 0.3048 0.381)
			(layers "F.Cu" "F.Mask" "F.Paste")
			(net "GND")
		)
	)
	(footprint ""
		(layer "F.Cu")
		(at 458.244194 -46.264576 -90)
		(property "Reference" "PR832"
			(at 0 0 270)
			(layer "F.SilkS")
			(hide yes)
			(effects
				(font
					(size 1.27 1.27)
				)
			)
		)
		(property "Value" ""
			(at 0 0 270)
			(layer "F.Fab")
			(effects
				(font
					(size 1.27 1.27)
				)
			)
		)
		(duplicate_pad_numbers_are_jumpers no)
		(fp_line
			(start -0.7874 0.4064)
			(end -0.7874 -0.4064)
			(stroke
				(width 0.1524)
				(type default)
			)
			(layer "F.SilkS")
		)
		(fp_line
			(start 0.7874 0.4064)
			(end -0.7874 0.4064)
			(stroke
				(width 0.1524)
				(type default)
			)
			(layer "F.SilkS")
		)
		(fp_line
			(start -0.7874 -0.4064)
			(end 0.7874 -0.4064)
			(stroke
				(width 0.1524)
				(type default)
			)
			(layer "F.SilkS")
		)
		(fp_line
			(start 0.7874 -0.4064)
			(end 0.7874 0.4064)
			(stroke
				(width 0.1524)
				(type default)
			)
			(layer "F.SilkS")
		)
		(fp_line
			(start -0.67945 0.3048)
			(end -0.67945 -0.305054)
			(stroke
				(width 0.1)
				(type default)
			)
			(layer "F.Fab")
		)
		(fp_line
			(start -0.12065 0.3048)
			(end -0.67945 0.3048)
			(stroke
				(width 0.1)
				(type default)
			)
			(layer "F.Fab")
		)
		(fp_line
			(start 0.120396 0.3048)
			(end 0.120396 0.2794)
			(stroke
				(width 0.1)
				(type default)
			)
			(layer "F.Fab")
		)
		(fp_line
			(start 0.67945 0.3048)
			(end 0.120396 0.3048)
			(stroke
				(width 0.1)
				(type default)
			)
			(layer "F.Fab")
		)
		(fp_line
			(start -0.12065 0.2794)
			(end -0.12065 0.3048)
			(stroke
				(width 0.1)
				(type default)
			)
			(layer "F.Fab")
		)
		(fp_line
			(start 0.120396 0.2794)
			(end -0.12065 0.2794)
			(stroke
				(width 0.1)
				(type default)
			)
			(layer "F.Fab")
		)
		(fp_line
			(start -0.12065 -0.2794)
			(end 0.12065 -0.2794)
			(stroke
				(width 0.1)
				(type default)
			)
			(layer "F.Fab")
		)
		(fp_line
			(start 0.12065 -0.2794)
			(end 0.12065 -0.3048)
			(stroke
				(width 0.1)
				(type default)
			)
			(layer "F.Fab")
		)
		(fp_line
			(start 0.12065 -0.3048)
			(end 0.67945 -0.3048)
			(stroke
				(width 0.1)
				(type default)
			)
			(layer "F.Fab")
		)
		(fp_line
			(start 0.67945 -0.3048)
			(end 0.67945 0.3048)
			(stroke
				(width 0.1)
				(type default)
			)
			(layer "F.Fab")
		)
		(fp_line
			(start -0.67945 -0.305054)
			(end -0.12065 -0.305054)
			(stroke
				(width 0.1)
				(type default)
			)
			(layer "F.Fab")
		)
		(fp_line
			(start -0.12065 -0.305054)
			(end -0.12065 -0.2794)
			(stroke
				(width 0.1)
				(type default)
			)
			(layer "F.Fab")
		)
		(pad "1" smd circle
			(at -0.40005 0 270)
			(size 0 0)
			(layers "F.Cu" "F.Mask" "F.Paste")
			(net "P3V3_AUX_MODE")
		)
		(pad "2" smd circle
			(at 0.40005 0 270)
			(size 0 0)
			(layers "F.Cu" "F.Mask" "F.Paste")
			(net "GND")
		)
	)
	(footprint ""
		(layer "F.Cu")
		(at 223.70288 -44.922948)
		(property "Reference" "R3534"
			(at 0 0 0)
			(layer "F.SilkS")
			(hide yes)
			(effects
				(font
					(size 1.27 1.27)
				)
			)
		)
		(property "Value" ""
			(at 0 0 0)
			(layer "F.Fab")
			(effects
				(font
					(size 1.27 1.27)
				)
			)
		)
		(duplicate_pad_numbers_are_jumpers no)
		(fp_line
			(start -0.7874 -0.4064)
			(end 0.7874 -0.4064)
			(stroke
				(width 0.1524)
				(type default)
			)
			(layer "F.SilkS")
		)
		(fp_line
			(start -0.7874 0.4064)
			(end -0.7874 -0.4064)
			(stroke
				(width 0.1524)
				(type default)
			)
			(layer "F.SilkS")
		)
		(fp_line
			(start 0.7874 -0.4064)
			(end 0.7874 0.4064)
			(stroke
				(width 0.1524)
				(type default)
			)
			(layer "F.SilkS")
		)
		(fp_line
			(start 0.7874 0.4064)
			(end -0.7874 0.4064)
			(stroke
				(width 0.1524)
				(type default)
			)
			(layer "F.SilkS")
		)
		(fp_line
			(start -0.67945 -0.305054)
			(end -0.12065 -0.305054)
			(stroke
				(width 0.1)
				(type default)
			)
			(layer "F.Fab")
		)
		(fp_line
			(start -0.67945 0.3048)
			(end -0.67945 -0.305054)
			(stroke
				(width 0.1)
				(type default)
			)
			(layer "F.Fab")
		)
		(fp_line
			(start -0.12065 -0.305054)
			(end -0.12065 -0.2794)
			(stroke
				(width 0.1)
				(type default)
			)
			(layer "F.Fab")
		)
		(fp_line
			(start -0.12065 -0.2794)
			(end 0.12065 -0.2794)
			(stroke
				(width 0.1)
				(type default)
			)
			(layer "F.Fab")
		)
		(fp_line
			(start -0.12065 0.2794)
			(end -0.12065 0.3048)
			(stroke
				(width 0.1)
				(type default)
			)
			(layer "F.Fab")
		)
		(fp_line
			(start -0.12065 0.3048)
			(end -0.67945 0.3048)
			(stroke
				(width 0.1)
				(type default)
			)
			(layer "F.Fab")
		)
		(fp_line
			(start 0.120396 0.2794)
			(end -0.12065 0.2794)
			(stroke
				(width 0.1)
				(type default)
			)
			(layer "F.Fab")
		)
		(fp_line
			(start 0.120396 0.3048)
			(end 0.120396 0.2794)
			(stroke
				(width 0.1)
				(type default)
			)
			(layer "F.Fab")
		)
		(fp_line
			(start 0.12065 -0.3048)
			(end 0.67945 -0.3048)
			(stroke
				(width 0.1)
				(type default)
			)
			(layer "F.Fab")
		)
		(fp_line
			(start 0.12065 -0.2794)
			(end 0.12065 -0.3048)
			(stroke
				(width 0.1)
				(type default)
			)
			(layer "F.Fab")
		)
		(fp_line
			(start 0.67945 -0.3048)
			(end 0.67945 0.3048)
			(stroke
				(width 0.1)
				(type default)
			)
			(layer "F.Fab")
		)
		(fp_line
			(start 0.67945 0.3048)
			(end 0.120396 0.3048)
			(stroke
				(width 0.1)
				(type default)
			)
			(layer "F.Fab")
		)
		(pad "1" smd circle
			(at -0.40005 0)
			(size 0 0)
			(layers "F.Cu" "F.Mask" "F.Paste")
			(net "SMB_E1S_3V3AUX_ISO_SDA_R")
		)
		(pad "2" smd circle
			(at 0.40005 0)
			(size 0 0)
			(layers "F.Cu" "F.Mask" "F.Paste")
			(net "SMB_E1S_3V3AUX_ISO_SDA")
		)
	)
)
